(kicad_pcb
	(version 20260206)
	(generator "pcbnew")
	(generator_version "10.0")
	(general
		(thickness 1.6)
		(legacy_teardrops no)
	)
	(paper "A4")
	(title_block
		(title "Bryce Canyon_R.DPB_16317-1_OCP.brd")
		(comment 1 "Bryce Canyon / footprints 1448-1454 of 2099")
	)
	(layers
		(0 "F.Cu" signal "TOP")
		(4 "In1.Cu" signal "L2GND")
		(6 "In2.Cu" signal "L3")
		(8 "In3.Cu" signal "L4VCC")
		(10 "In4.Cu" signal "L5VCC")
		(12 "In5.Cu" signal "L6")
		(14 "In6.Cu" signal "L7GND")
		(2 "B.Cu" signal "BOTTOM")
		(9 "F.Adhes" user "F.Adhesive")
		(11 "B.Adhes" user "B.Adhesive")
		(13 "F.Paste" user "Package Geometry/Pastemask Top")
		(15 "B.Paste" user "Package Geometry/Pastemask Bottom")
		(5 "F.SilkS" user "Ref Des/Silkscreen Top")
		(7 "B.SilkS" user "Ref Des/Silkscreen Bottom")
		(1 "F.Mask" user "Board Geometry/Soldermask Top")
		(3 "B.Mask" user "Board Geometry/Soldermask Bottom")
		(17 "Dwgs.User" user "User.Drawings")
		(19 "Cmts.User" user "User.Comments")
		(21 "Eco1.User" user "User.Eco1")
		(23 "Eco2.User" user "User.Eco2")
		(25 "Edge.Cuts" user "Board Geometry/Outline")
		(27 "Margin" user)
		(31 "F.CrtYd" user "Package Geometry/Place Bound Top")
		(29 "B.CrtYd" user "Package Geometry/Place Bound Bottom")
		(35 "F.Fab" user "Ref Des/Assembly Top")
		(33 "B.Fab" user "Ref Des/Assembly Bottom")
	)
	(footprint ""
		(layer "F.Cu")
		(at 212.5218 -204.343 90)
		(property "Reference" "C10"
			(at 0 0 90)
			(layer "F.SilkS")
			(hide yes)
			(effects
				(font
					(size 1.27 1.27)
				)
			)
		)
		(property "Value" "SCD1U16V2KX-3GP"
			(at 1.1811 -2.7051 90)
			(unlocked yes)
			(layer "F.Fab")
			(hide yes)
			(effects
				(font
					(size 1.016 1.016)
					(thickness 0.1524)
				)
			)
		)
		(property "Device Type" "C402H22"
			(at 1.1811 -4.2291 90)
			(unlocked yes)
			(layer "F.Fab")
			(hide yes)
			(effects
				(font
					(size 1.016 1.016)
					(thickness 0.1524)
				)
			)
		)
		(duplicate_pad_numbers_are_jumpers no)
		(fp_rect
			(start -0.4318 0.9525)
			(end 0.4318 -0.9525)
			(stroke
				(width 0)
				(type default)
			)
			(fill no)
			(layer "F.CrtYd")
		)
		(fp_rect
			(start -0.4318 0.9525)
			(end 0.4318 -0.9525)
			(stroke
				(width 0)
				(type default)
			)
			(fill no)
			(layer "F.Fab")
		)
		(pad "1" smd custom
			(at 0 -0.4445 90)
			(size 0.1524 0.1524)
			(layers "F.Cu" "F.Mask" "F.Paste")
			(net "P3V3_STBY_B")
			(options
				(clearance outline)
				(anchor circle)
			)
			(primitives
				(gr_poly
					(pts
						(arc
							(start 0.3048 -0.2032)
							(mid 0.275042 -0.275042)
							(end 0.2032 -0.3048)
						)
						(arc
							(start -0.2032 -0.3048)
							(mid -0.275042 -0.275042)
							(end -0.3048 -0.2032)
						)
						(arc
							(start -0.3048 0.2032)
							(mid -0.275042 0.275042)
							(end -0.2032 0.3048)
						)
						(arc
							(start 0.2032 0.3048)
							(mid 0.275042 0.275042)
							(end 0.3048 0.2032)
						)
					)
					(width 0)
					(fill yes)
				)
			)
		)
		(pad "2" smd custom
			(at 0 0.4445 90)
			(size 0.1524 0.1524)
			(layers "F.Cu" "F.Mask" "F.Paste")
			(net "GND")
			(options
				(clearance outline)
				(anchor circle)
			)
			(primitives
				(gr_poly
					(pts
						(arc
							(start 0.3048 -0.2032)
							(mid 0.275042 -0.275042)
							(end 0.2032 -0.3048)
						)
						(arc
							(start -0.2032 -0.3048)
							(mid -0.275042 -0.275042)
							(end -0.3048 -0.2032)
						)
						(arc
							(start -0.3048 0.2032)
							(mid -0.275042 0.275042)
							(end -0.2032 0.3048)
						)
						(arc
							(start 0.2032 0.3048)
							(mid 0.275042 0.275042)
							(end 0.3048 0.2032)
						)
					)
					(width 0)
					(fill yes)
				)
			)
		)
	)
	(footprint ""
		(layer "F.Cu")
		(at 244.662452 -362.284772)
		(property "Reference" "R1051"
			(at 0 0 0)
			(layer "F.SilkS")
			(hide yes)
			(effects
				(font
					(size 1.27 1.27)
				)
			)
		)
		(property "Value" "4K99R2F-L-GP"
			(at 0.064008 -3.993896 0)
			(unlocked yes)
			(layer "F.Fab")
			(hide yes)
			(effects
				(font
					(size 1.016 1.016)
					(thickness 0.1524)
				)
			)
		)
		(property "Device Type" "R402H16"
			(at 0.064008 -5.517896 0)
			(unlocked yes)
			(layer "F.Fab")
			(hide yes)
			(effects
				(font
					(size 1.016 1.016)
					(thickness 0.1524)
				)
			)
		)
		(duplicate_pad_numbers_are_jumpers no)
		(fp_line
			(start -0.508 -0.9398)
			(end -0.508 0.9398)
			(stroke
				(width 0.1524)
				(type default)
			)
			(layer "F.SilkS")
		)
		(fp_line
			(start 0.508 -0.9398)
			(end -0.508 -0.9398)
			(stroke
				(width 0.1524)
				(type default)
			)
			(layer "F.SilkS")
		)
		(fp_rect
			(start -0.508 0.9398)
			(end 0.508 -0.9398)
			(stroke
				(width 0)
				(type default)
			)
			(fill no)
			(layer "F.CrtYd")
		)
		(fp_rect
			(start -0.508 0.9398)
			(end 0.508 -0.9398)
			(stroke
				(width 0)
				(type default)
			)
			(fill no)
			(layer "F.Fab")
		)
		(pad "1" smd custom
			(at 0 -0.4445)
			(size 0.1397 0.1397)
			(layers "F.Cu" "F.Mask" "F.Paste")
			(net "MB3_CM_UV_R")
			(options
				(clearance outline)
				(anchor circle)
			)
			(primitives
				(gr_poly
					(pts
						(arc
							(start -0.1778 -0.2794)
							(mid -0.249642 -0.249642)
							(end -0.2794 -0.1778)
						)
						(arc
							(start -0.2794 0.1778)
							(mid -0.249642 0.249642)
							(end -0.1778 0.2794)
						)
						(arc
							(start 0.1778 0.2794)
							(mid 0.249642 0.249642)
							(end 0.2794 0.1778)
						)
						(arc
							(start 0.2794 -0.1778)
							(mid 0.249642 -0.249642)
							(end 0.1778 -0.2794)
						)
					)
					(width 0)
					(fill yes)
				)
			)
		)
		(pad "2" smd custom
			(at 0 0.4445)
			(size 0.1397 0.1397)
			(layers "F.Cu" "F.Mask" "F.Paste")
			(net "AGND_CURRENT_DPB")
			(options
				(clearance outline)
				(anchor circle)
			)
			(primitives
				(gr_poly
					(pts
						(arc
							(start -0.1778 -0.2794)
							(mid -0.249642 -0.249642)
							(end -0.2794 -0.1778)
						)
						(arc
							(start -0.2794 0.1778)
							(mid -0.249642 0.249642)
							(end -0.1778 0.2794)
						)
						(arc
							(start 0.1778 0.2794)
							(mid 0.249642 0.249642)
							(end 0.2794 0.1778)
						)
						(arc
							(start 0.2794 -0.1778)
							(mid 0.249642 -0.249642)
							(end 0.1778 -0.2794)
						)
					)
					(width 0)
					(fill yes)
				)
			)
		)
	)
	(footprint ""
		(layer "F.Cu")
		(at 467.741 -250.571 90)
		(property "Reference" "R344"
			(at 0 0 90)
			(layer "F.SilkS")
			(hide yes)
			(effects
				(font
					(size 1.27 1.27)
				)
			)
		)
		(property "Value" "4K7R2J-2-GP"
			(at 0.064008 -3.993896 90)
			(unlocked yes)
			(layer "F.Fab")
			(hide yes)
			(effects
				(font
					(size 1.016 1.016)
					(thickness 0.1524)
				)
			)
		)
		(property "Device Type" "R402H16"
			(at 0.064008 -5.517896 90)
			(unlocked yes)
			(layer "F.Fab")
			(hide yes)
			(effects
				(font
					(size 1.016 1.016)
					(thickness 0.1524)
				)
			)
		)
		(duplicate_pad_numbers_are_jumpers no)
		(fp_line
			(start 0.508 -0.9398)
			(end -0.508 -0.9398)
			(stroke
				(width 0.1524)
				(type default)
			)
			(layer "F.SilkS")
		)
		(fp_line
			(start -0.508 -0.9398)
			(end -0.508 0.9398)
			(stroke
				(width 0.1524)
				(type default)
			)
			(layer "F.SilkS")
		)
		(fp_rect
			(start -0.508 0.9398)
			(end 0.508 -0.9398)
			(stroke
				(width 0)
				(type default)
			)
			(fill no)
			(layer "F.CrtYd")
		)
		(fp_rect
			(start -0.508 0.9398)
			(end 0.508 -0.9398)
			(stroke
				(width 0)
				(type default)
			)
			(fill no)
			(layer "F.Fab")
		)
		(pad "1" smd custom
			(at 0 -0.4445 90)
			(size 0.1397 0.1397)
			(layers "F.Cu" "F.Mask" "F.Paste")
			(net "P12V_B")
			(options
				(clearance outline)
				(anchor circle)
			)
			(primitives
				(gr_poly
					(pts
						(arc
							(start -0.1778 -0.2794)
							(mid -0.249642 -0.249642)
							(end -0.2794 -0.1778)
						)
						(arc
							(start -0.2794 0.1778)
							(mid -0.249642 0.249642)
							(end -0.1778 0.2794)
						)
						(arc
							(start 0.1778 0.2794)
							(mid 0.249642 0.249642)
							(end 0.2794 0.1778)
						)
						(arc
							(start 0.2794 -0.1778)
							(mid 0.249642 -0.249642)
							(end 0.1778 -0.2794)
						)
					)
					(width 0)
					(fill yes)
				)
			)
		)
		(pad "2" smd custom
			(at 0 0.4445 90)
			(size 0.1397 0.1397)
			(layers "F.Cu" "F.Mask" "F.Paste")
			(net "SW_HDD_R11")
			(options
				(clearance outline)
				(anchor circle)
			)
			(primitives
				(gr_poly
					(pts
						(arc
							(start -0.1778 -0.2794)
							(mid -0.249642 -0.249642)
							(end -0.2794 -0.1778)
						)
						(arc
							(start -0.2794 0.1778)
							(mid -0.249642 0.249642)
							(end -0.1778 0.2794)
						)
						(arc
							(start 0.1778 0.2794)
							(mid 0.249642 0.249642)
							(end 0.2794 0.1778)
						)
						(arc
							(start 0.2794 -0.1778)
							(mid 0.249642 -0.249642)
							(end 0.1778 -0.2794)
						)
					)
					(width 0)
					(fill yes)
				)
			)
		)
	)
	(footprint ""
		(layer "F.Cu")
		(at 177.419 -361.696)
		(property "Reference" "C540"
			(at 0 0 0)
			(layer "F.SilkS")
			(hide yes)
			(effects
				(font
					(size 1.27 1.27)
				)
			)
		)
		(property "Value" "SCD22U16V2KX-GP"
			(at 1.1811 -2.7051 0)
			(unlocked yes)
			(layer "F.Fab")
			(hide yes)
			(effects
				(font
					(size 1.016 1.016)
					(thickness 0.1524)
				)
			)
		)
		(property "Device Type" "C402H22"
			(at 1.1811 -4.2291 0)
			(unlocked yes)
			(layer "F.Fab")
			(hide yes)
			(effects
				(font
					(size 1.016 1.016)
					(thickness 0.1524)
				)
			)
		)
		(duplicate_pad_numbers_are_jumpers no)
		(fp_rect
			(start -0.4318 0.9525)
			(end 0.4318 -0.9525)
			(stroke
				(width 0)
				(type default)
			)
			(fill no)
			(layer "F.CrtYd")
		)
		(fp_rect
			(start -0.4318 0.9525)
			(end 0.4318 -0.9525)
			(stroke
				(width 0)
				(type default)
			)
			(fill no)
			(layer "F.Fab")
		)
		(pad "1" smd custom
			(at 0 -0.4445)
			(size 0.1524 0.1524)
			(layers "F.Cu" "F.Mask" "F.Paste")
			(net "MB0_TIME_R")
			(options
				(clearance outline)
				(anchor circle)
			)
			(primitives
				(gr_poly
					(pts
						(arc
							(start 0.3048 -0.2032)
							(mid 0.275042 -0.275042)
							(end 0.2032 -0.3048)
						)
						(arc
							(start -0.2032 -0.3048)
							(mid -0.275042 -0.275042)
							(end -0.3048 -0.2032)
						)
						(arc
							(start -0.3048 0.2032)
							(mid -0.275042 0.275042)
							(end -0.2032 0.3048)
						)
						(arc
							(start 0.2032 0.3048)
							(mid 0.275042 0.275042)
							(end 0.3048 0.2032)
						)
					)
					(width 0)
					(fill yes)
				)
			)
		)
		(pad "2" smd custom
			(at 0 0.4445)
			(size 0.1524 0.1524)
			(layers "F.Cu" "F.Mask" "F.Paste")
			(net "AGND_CURRENT_MON")
			(options
				(clearance outline)
				(anchor circle)
			)
			(primitives
				(gr_poly
					(pts
						(arc
							(start 0.3048 -0.2032)
							(mid 0.275042 -0.275042)
							(end 0.2032 -0.3048)
						)
						(arc
							(start -0.2032 -0.3048)
							(mid -0.275042 -0.275042)
							(end -0.3048 -0.2032)
						)
						(arc
							(start -0.3048 0.2032)
							(mid -0.275042 0.275042)
							(end -0.2032 0.3048)
						)
						(arc
							(start 0.2032 0.3048)
							(mid 0.275042 0.275042)
							(end 0.3048 0.2032)
						)
					)
					(width 0)
					(fill yes)
				)
			)
		)
	)
	(footprint ""
		(layer "F.Cu")
		(at 299.722286 -333.032862 180)
		(property "Reference" "C22"
			(at 0 0 180)
			(layer "F.SilkS")
			(hide yes)
			(effects
				(font
					(size 1.27 1.27)
				)
			)
		)
		(property "Value" "SC1U16V3KX-5GP"
			(at 0 -2.8194 180)
			(unlocked yes)
			(layer "F.Fab")
			(hide yes)
			(effects
				(font
					(size 1.016 1.016)
					(thickness 0.1524)
				)
			)
		)
		(property "Device Type" "C603H36"
			(at 0 -4.3434 180)
			(unlocked yes)
			(layer "F.Fab")
			(hide yes)
			(effects
				(font
					(size 1.016 1.016)
					(thickness 0.1524)
				)
			)
		)
		(duplicate_pad_numbers_are_jumpers no)
		(fp_line
			(start 0.508 0)
			(end -0.508 0)
			(stroke
				(width 0.2032)
				(type default)
			)
			(layer "F.SilkS")
		)
		(fp_rect
			(start -0.5842 1.3335)
			(end 0.5842 -1.3335)
			(stroke
				(width 0)
				(type default)
			)
			(fill no)
			(layer "F.CrtYd")
		)
		(fp_rect
			(start -0.5842 1.3335)
			(end 0.5842 -1.3335)
			(stroke
				(width 0)
				(type default)
			)
			(fill no)
			(layer "F.Fab")
		)
		(pad "1" smd custom
			(at 0 -0.762 180)
			(size 0.2159 0.2159)
			(layers "F.Cu" "F.Mask" "F.Paste")
			(net "P3V3_IN")
			(options
				(clearance outline)
				(anchor circle)
			)
			(primitives
				(gr_poly
					(pts
						(arc
							(start -0.3302 -0.4318)
							(mid -0.402042 -0.402042)
							(end -0.4318 -0.3302)
						)
						(arc
							(start -0.4318 0.3302)
							(mid -0.402042 0.402042)
							(end -0.3302 0.4318)
						)
						(arc
							(start 0.3302 0.4318)
							(mid 0.402042 0.402042)
							(end 0.4318 0.3302)
						)
						(arc
							(start 0.4318 -0.3302)
							(mid 0.402042 -0.402042)
							(end 0.3302 -0.4318)
						)
					)
					(width 0)
					(fill yes)
				)
			)
		)
		(pad "2" smd custom
			(at 0 0.762 180)
			(size 0.2159 0.2159)
			(layers "F.Cu" "F.Mask" "F.Paste")
			(net "GND")
			(options
				(clearance outline)
				(anchor circle)
			)
			(primitives
				(gr_poly
					(pts
						(arc
							(start -0.3302 -0.4318)
							(mid -0.402042 -0.402042)
							(end -0.4318 -0.3302)
						)
						(arc
							(start -0.4318 0.3302)
							(mid -0.402042 0.402042)
							(end -0.3302 0.4318)
						)
						(arc
							(start 0.3302 0.4318)
							(mid 0.402042 0.402042)
							(end 0.4318 0.3302)
						)
						(arc
							(start 0.4318 -0.3302)
							(mid 0.402042 -0.402042)
							(end 0.3302 -0.4318)
						)
					)
					(width 0)
					(fill yes)
				)
			)
		)
	)
	(footprint ""
		(layer "F.Cu")
		(at 220.6752 -193.294 90)
		(property "Reference" "R34"
			(at 0 0 90)
			(layer "F.SilkS")
			(hide yes)
			(effects
				(font
					(size 1.27 1.27)
				)
			)
		)
		(property "Value" "4K7R2F-GP"
			(at 0.064008 -3.993896 90)
			(unlocked yes)
			(layer "F.Fab")
			(hide yes)
			(effects
				(font
					(size 1.016 1.016)
					(thickness 0.1524)
				)
			)
		)
		(property "Device Type" "R402H16"
			(at 0.064008 -5.517896 90)
			(unlocked yes)
			(layer "F.Fab")
			(hide yes)
			(effects
				(font
					(size 1.016 1.016)
					(thickness 0.1524)
				)
			)
		)
		(duplicate_pad_numbers_are_jumpers no)
		(fp_line
			(start 0.508 -0.9398)
			(end -0.508 -0.9398)
			(stroke
				(width 0.1524)
				(type default)
			)
			(layer "F.SilkS")
		)
		(fp_line
			(start -0.508 -0.9398)
			(end -0.508 0.9398)
			(stroke
				(width 0.1524)
				(type default)
			)
			(layer "F.SilkS")
		)
		(fp_rect
			(start -0.508 0.9398)
			(end 0.508 -0.9398)
			(stroke
				(width 0)
				(type default)
			)
			(fill no)
			(layer "F.CrtYd")
		)
		(fp_rect
			(start -0.508 0.9398)
			(end 0.508 -0.9398)
			(stroke
				(width 0)
				(type default)
			)
			(fill no)
			(layer "F.Fab")
		)
		(pad "1" smd custom
			(at 0 -0.4445 90)
			(size 0.1397 0.1397)
			(layers "F.Cu" "F.Mask" "F.Paste")
			(net "IO_EXP2_HDD_FAULT_A0")
			(options
				(clearance outline)
				(anchor circle)
			)
			(primitives
				(gr_poly
					(pts
						(arc
							(start -0.1778 -0.2794)
							(mid -0.249642 -0.249642)
							(end -0.2794 -0.1778)
						)
						(arc
							(start -0.2794 0.1778)
							(mid -0.249642 0.249642)
							(end -0.1778 0.2794)
						)
						(arc
							(start 0.1778 0.2794)
							(mid 0.249642 0.249642)
							(end 0.2794 0.1778)
						)
						(arc
							(start 0.2794 -0.1778)
							(mid 0.249642 -0.249642)
							(end 0.1778 -0.2794)
						)
					)
					(width 0)
					(fill yes)
				)
			)
		)
		(pad "2" smd custom
			(at 0 0.4445 90)
			(size 0.1397 0.1397)
			(layers "F.Cu" "F.Mask" "F.Paste")
			(net "GND")
			(options
				(clearance outline)
				(anchor circle)
			)
			(primitives
				(gr_poly
					(pts
						(arc
							(start -0.1778 -0.2794)
							(mid -0.249642 -0.249642)
							(end -0.2794 -0.1778)
						)
						(arc
							(start -0.2794 0.1778)
							(mid -0.249642 0.249642)
							(end -0.1778 0.2794)
						)
						(arc
							(start 0.1778 0.2794)
							(mid 0.249642 0.249642)
							(end 0.2794 0.1778)
						)
						(arc
							(start 0.2794 -0.1778)
							(mid 0.249642 -0.249642)
							(end 0.1778 -0.2794)
						)
					)
					(width 0)
					(fill yes)
				)
			)
		)
	)
	(footprint ""
		(layer "F.Cu")
		(at 399.923 -148.082)
		(property "Reference" "Q96"
			(at 0 0 0)
			(layer "F.SilkS")
			(hide yes)
			(effects
				(font
					(size 1.27 1.27)
				)
			)
		)
		(property "Value" "AO4407AL-GP"
			(at -3.707384 -1.5367 0)
			(unlocked yes)
			(layer "F.Fab")
			(hide yes)
			(effects
				(font
					(size 1.016 1.016)
					(thickness 0.1524)
				)
			)
		)
		(property "Device Type" "SOIC8H69"
			(at -3.707384 -3.0607 0)
			(unlocked yes)
			(layer "F.Fab")
			(hide yes)
			(effects
				(font
					(size 1.016 1.016)
					(thickness 0.1524)
				)
			)
		)
		(duplicate_pad_numbers_are_jumpers no)
		(fp_line
			(start -2.7432 -1.4224)
			(end -2.7432 1.4224)
			(stroke
				(width 0.1524)
				(type default)
			)
			(layer "F.SilkS")
		)
		(fp_line
			(start -2.7432 1.4224)
			(end -2.6416 1.4224)
			(stroke
				(width 0.1524)
				(type default)
			)
			(layer "F.SilkS")
		)
		(fp_line
			(start -2.7432 1.4224)
			(end 2.1336 1.4224)
			(stroke
				(width 0.1524)
				(type default)
			)
			(layer "F.SilkS")
		)
		(fp_line
			(start -2.7178 -0.508)
			(end -2.1844 -0.0508)
			(stroke
				(width 0.1524)
				(type default)
			)
			(layer "F.SilkS")
		)
		(fp_line
			(start -2.6289 3.4417)
			(end -2.6289 1.4732)
			(stroke
				(width 0.381)
				(type default)
			)
			(layer "F.SilkS")
		)
		(fp_line
			(start -2.1844 -0.0508)
			(end -2.7178 0.508)
			(stroke
				(width 0.1524)
				(type default)
			)
			(layer "F.SilkS")
		)
		(fp_line
			(start 2.1336 -1.4224)
			(end -2.7432 -1.4224)
			(stroke
				(width 0.1524)
				(type default)
			)
			(layer "F.SilkS")
		)
		(fp_line
			(start 2.1336 1.4224)
			(end 2.1336 -1.4224)
			(stroke
				(width 0.1524)
				(type default)
			)
			(layer "F.SilkS")
		)
		(fp_poly
			(pts
				(xy -2.2098 -1.4224) (xy -2.2098 1.4224) (xy 2.2098 1.4224) (xy 2.2098 -1.4224)
			)
			(stroke
				(width 0)
				(type default)
			)
			(fill yes)
			(layer "F.SilkS")
		)
		(fp_rect
			(start -2.450084 2.999994)
			(end 2.450084 -2.999994)
			(stroke
				(width 0)
				(type default)
			)
			(fill no)
			(layer "F.CrtYd")
		)
		(fp_poly
			(pts
				(xy -2.8194 3.6322) (xy -2.8194 -3.6322) (xy 2.8194 -3.6322) (xy 2.8194 1.18364) (xy 2.450084 1.18364)
				(xy 2.450084 -2.999994) (xy -2.450084 -2.999994) (xy -2.450084 2.999994) (xy 2.450084 2.999994)
				(xy 2.450084 1.18618) (xy 2.8194 1.18618) (xy 2.8194 3.6322)
			)
			(stroke
				(width 0)
				(type default)
			)
			(fill no)
			(layer "F.CrtYd")
		)
		(fp_rect
			(start -2.8194 3.6322)
			(end 2.8194 -3.6322)
			(stroke
				(width 0)
				(type default)
			)
			(fill no)
			(layer "F.Fab")
		)
		(pad "1" smd rect
			(at -1.905 2.54)
			(size 0.635 1.651)
			(layers "F.Cu" "F.Mask" "F.Paste")
			(net "P12V_B")
		)
		(pad "2" smd rect
			(at -0.635 2.54)
			(size 0.635 1.651)
			(layers "F.Cu" "F.Mask" "F.Paste")
			(net "P12V_B")
		)
		(pad "3" smd rect
			(at 0.635 2.54)
			(size 0.635 1.651)
			(layers "F.Cu" "F.Mask" "F.Paste")
			(net "P12V_B")
		)
		(pad "4" smd rect
			(at 1.905 2.54)
			(size 0.635 1.651)
			(layers "F.Cu" "F.Mask" "F.Paste")
			(net "SW_HDD_N20")
		)
		(pad "5" smd rect
			(at 1.905 -2.54)
			(size 0.635 1.651)
			(layers "F.Cu" "F.Mask" "F.Paste")
			(net "P12V_HDD20")
		)
		(pad "6" smd rect
			(at 0.635 -2.54)
			(size 0.635 1.651)
			(layers "F.Cu" "F.Mask" "F.Paste")
			(net "P12V_HDD20")
		)
		(pad "7" smd rect
			(at -0.635 -2.54)
			(size 0.635 1.651)
			(layers "F.Cu" "F.Mask" "F.Paste")
			(net "P12V_HDD20")
		)
		(pad "8" smd rect
			(at -1.905 -2.54)
			(size 0.635 1.651)
			(layers "F.Cu" "F.Mask" "F.Paste")
			(net "P12V_HDD20")
		)
	)
)
